# SCM (Grand Teton) — schematic netlist excerpt (pin names and nets, part order shuffled) for the footprints in the layout excerpt that follows; sources: Cadence DE-HDL packaged netlist, KiCad conversion of 12092022_DA0F0TMDCD0_F0T_Management_Board_D_brd_V3_OCP.brd

C244  Q_CAP  1UF 25V 10% X6S  pkg C0402  page 45 : A = P3V3_AUX ; B = GND
R604  Q_RES  750 1% CHIP  pkg 0402LF  page 47 : A = LED_POSTCODE_0 ; B = LED_POSTCODE_0_R

(kicad_pcb
	(version 20260206)
	(generator "pcbnew")
	(generator_version "10.0")
	(general
		(thickness 1.6)
		(legacy_teardrops no)
	)
	(paper "A4")
	(title_block
		(title "12092022_DA0F0TMDCD0_F0T_Management_Board_D_brd_V3_OCP.brd")
		(comment 1 "Grand Teton / footprints 65-66 of 1440")
	)
	(layers
		(0 "F.Cu" signal "TOP")
		(4 "In1.Cu" signal "GND")
		(6 "In2.Cu" signal "IN1")
		(8 "In3.Cu" signal "GND1")
		(10 "In4.Cu" signal "IN2")
		(12 "In5.Cu" signal "VCC")
		(14 "In6.Cu" signal "VCC1")
		(16 "In7.Cu" signal "IN3")
		(18 "In8.Cu" signal "GND2")
		(20 "In9.Cu" signal "IN4")
		(22 "In10.Cu" signal "GND3")
		(2 "B.Cu" signal "BOTTOM")
		(9 "F.Adhes" user "F.Adhesive")
		(11 "B.Adhes" user "B.Adhesive")
		(13 "F.Paste" user "Package Geometry/Pastemask Top")
		(15 "B.Paste" user "Package Geometry/Pastemask Bottom")
		(5 "F.SilkS" user "Ref Des/Silkscreen Top")
		(7 "B.SilkS" user "Ref Des/Silkscreen Bottom")
		(1 "F.Mask" user "Board Geometry/Soldermask Top")
		(3 "B.Mask" user "Board Geometry/Soldermask Bottom")
		(17 "Dwgs.User" user "User.Drawings")
		(19 "Cmts.User" user "User.Comments")
		(21 "Eco1.User" user "User.Eco1")
		(23 "Eco2.User" user "User.Eco2")
		(25 "Edge.Cuts" user "Board Geometry/Outline")
		(27 "Margin" user)
		(31 "F.CrtYd" user "Package Geometry/Place Bound Top")
		(29 "B.CrtYd" user "Package Geometry/Place Bound Bottom")
		(35 "F.Fab" user "Ref Des/Assembly Top")
		(33 "B.Fab" user "Ref Des/Assembly Bottom")
	)
	(footprint ""
		(layer "F.Cu")
		(at 36.56203 -88.937592 -90)
		(property "Reference" "C244"
			(at 0 0 270)
			(layer "F.SilkS")
			(hide yes)
			(effects
				(font
					(size 1.27 1.27)
				)
			)
		)
		(property "Value" ""
			(at 0 0 270)
			(layer "F.Fab")
			(effects
				(font
					(size 1.27 1.27)
				)
			)
		)
		(duplicate_pad_numbers_are_jumpers no)
		(fp_line
			(start -0.7874 0.4064)
			(end -0.7874 -0.4064)
			(stroke
				(width 0.1524)
				(type default)
			)
			(layer "F.SilkS")
		)
		(fp_line
			(start 0.7874 0.4064)
			(end -0.7874 0.4064)
			(stroke
				(width 0.1524)
				(type default)
			)
			(layer "F.SilkS")
		)
		(fp_line
			(start -0.7874 -0.4064)
			(end 0.7874 -0.4064)
			(stroke
				(width 0.1524)
				(type default)
			)
			(layer "F.SilkS")
		)
		(fp_line
			(start 0.7874 -0.4064)
			(end 0.7874 0.4064)
			(stroke
				(width 0.1524)
				(type default)
			)
			(layer "F.SilkS")
		)
		(fp_line
			(start -0.67945 0.3048)
			(end -0.67945 -0.305054)
			(stroke
				(width 0.1)
				(type default)
			)
			(layer "F.Fab")
		)
		(fp_line
			(start -0.12065 0.3048)
			(end -0.67945 0.3048)
			(stroke
				(width 0.1)
				(type default)
			)
			(layer "F.Fab")
		)
		(fp_line
			(start 0.120396 0.3048)
			(end 0.120396 0.2794)
			(stroke
				(width 0.1)
				(type default)
			)
			(layer "F.Fab")
		)
		(fp_line
			(start 0.67945 0.3048)
			(end 0.120396 0.3048)
			(stroke
				(width 0.1)
				(type default)
			)
			(layer "F.Fab")
		)
		(fp_line
			(start -0.12065 0.2794)
			(end -0.12065 0.3048)
			(stroke
				(width 0.1)
				(type default)
			)
			(layer "F.Fab")
		)
		(fp_line
			(start 0.120396 0.2794)
			(end -0.12065 0.2794)
			(stroke
				(width 0.1)
				(type default)
			)
			(layer "F.Fab")
		)
		(fp_line
			(start -0.12065 -0.2794)
			(end 0.12065 -0.2794)
			(stroke
				(width 0.1)
				(type default)
			)
			(layer "F.Fab")
		)
		(fp_line
			(start 0.12065 -0.2794)
			(end 0.12065 -0.3048)
			(stroke
				(width 0.1)
				(type default)
			)
			(layer "F.Fab")
		)
		(fp_line
			(start 0.12065 -0.3048)
			(end 0.67945 -0.3048)
			(stroke
				(width 0.1)
				(type default)
			)
			(layer "F.Fab")
		)
		(fp_line
			(start 0.67945 -0.3048)
			(end 0.67945 0.3048)
			(stroke
				(width 0.1)
				(type default)
			)
			(layer "F.Fab")
		)
		(fp_line
			(start -0.67945 -0.305054)
			(end -0.12065 -0.305054)
			(stroke
				(width 0.1)
				(type default)
			)
			(layer "F.Fab")
		)
		(fp_line
			(start -0.12065 -0.305054)
			(end -0.12065 -0.2794)
			(stroke
				(width 0.1)
				(type default)
			)
			(layer "F.Fab")
		)
		(pad "1" smd circle
			(at -0.40005 0 270)
			(size 0 0)
			(layers "F.Cu" "F.Mask" "F.Paste")
			(net "P3V3_AUX")
		)
		(pad "2" smd circle
			(at 0.40005 0 270)
			(size 0 0)
			(layers "F.Cu" "F.Mask" "F.Paste")
			(net "GND")
		)
	)
	(footprint ""
		(layer "F.Cu")
		(at 80.280764 -28.54579 90)
		(property "Reference" "R604"
			(at 0 0 90)
			(layer "F.SilkS")
			(hide yes)
			(effects
				(font
					(size 1.27 1.27)
				)
			)
		)
		(property "Value" ""
			(at 0 0 90)
			(layer "F.Fab")
			(effects
				(font
					(size 1.27 1.27)
				)
			)
		)
		(duplicate_pad_numbers_are_jumpers no)
		(fp_line
			(start 0.7874 -0.4064)
			(end 0.7874 0.4064)
			(stroke
				(width 0.1524)
				(type default)
			)
			(layer "F.SilkS")
		)
		(fp_line
			(start -0.7874 -0.4064)
			(end 0.7874 -0.4064)
			(stroke
				(width 0.1524)
				(type default)
			)
			(layer "F.SilkS")
		)
		(fp_line
			(start 0.7874 0.4064)
			(end -0.7874 0.4064)
			(stroke
				(width 0.1524)
				(type default)
			)
			(layer "F.SilkS")
		)
		(fp_line
			(start -0.7874 0.4064)
			(end -0.7874 -0.4064)
			(stroke
				(width 0.1524)
				(type default)
			)
			(layer "F.SilkS")
		)
		(fp_line
			(start -0.12065 -0.305054)
			(end -0.12065 -0.2794)
			(stroke
				(width 0.1)
				(type default)
			)
			(layer "F.Fab")
		)
		(fp_line
			(start -0.67945 -0.305054)
			(end -0.12065 -0.305054)
			(stroke
				(width 0.1)
				(type default)
			)
			(layer "F.Fab")
		)
		(fp_line
			(start 0.67945 -0.3048)
			(end 0.67945 0.3048)
			(stroke
				(width 0.1)
				(type default)
			)
			(layer "F.Fab")
		)
		(fp_line
			(start 0.12065 -0.3048)
			(end 0.67945 -0.3048)
			(stroke
				(width 0.1)
				(type default)
			)
			(layer "F.Fab")
		)
		(fp_line
			(start 0.12065 -0.2794)
			(end 0.12065 -0.3048)
			(stroke
				(width 0.1)
				(type default)
			)
			(layer "F.Fab")
		)
		(fp_line
			(start -0.12065 -0.2794)
			(end 0.12065 -0.2794)
			(stroke
				(width 0.1)
				(type default)
			)
			(layer "F.Fab")
		)
		(fp_line
			(start 0.120396 0.2794)
			(end -0.12065 0.2794)
			(stroke
				(width 0.1)
				(type default)
			)
			(layer "F.Fab")
		)
		(fp_line
			(start -0.12065 0.2794)
			(end -0.12065 0.3048)
			(stroke
				(width 0.1)
				(type default)
			)
			(layer "F.Fab")
		)
		(fp_line
			(start 0.67945 0.3048)
			(end 0.120396 0.3048)
			(stroke
				(width 0.1)
				(type default)
			)
			(layer "F.Fab")
		)
		(fp_line
			(start 0.120396 0.3048)
			(end 0.120396 0.2794)
			(stroke
				(width 0.1)
				(type default)
			)
			(layer "F.Fab")
		)
		(fp_line
			(start -0.12065 0.3048)
			(end -0.67945 0.3048)
			(stroke
				(width 0.1)
				(type default)
			)
			(layer "F.Fab")
		)
		(fp_line
			(start -0.67945 0.3048)
			(end -0.67945 -0.305054)
			(stroke
				(width 0.1)
				(type default)
			)
			(layer "F.Fab")
		)
		(pad "1" smd circle
			(at -0.40005 0 90)
			(size 0 0)
			(layers "F.Cu" "F.Mask" "F.Paste")
			(net "LED_POSTCODE_0")
		)
		(pad "2" smd circle
			(at 0.40005 0 90)
			(size 0 0)
			(layers "F.Cu" "F.Mask" "F.Paste")
			(net "LED_POSTCODE_0_R")
		)
	)
)
